G04*
G04 #@! TF.GenerationSoftware,Altium Limited,Altium Designer,23.7.1 (13)*
G04*
G04 Layer_Color=8388736*
%FSLAX25Y25*%
%MOIN*%
G70*
G04*
G04 #@! TF.SameCoordinates,AF00DCEB-AC48-4C7C-91EA-99F42E284231*
G04*
G04*
G04 #@! TF.FilePolarity,Positive*
G04*
G01*
G75*
%ADD15C,0.00787*%
D15*
X59292Y-126663D02*
Y-119774D01*
X55552Y-126663D02*
X59292D01*
X55552D02*
Y-119774D01*
X59292D01*
X58210Y-106289D02*
X64903D01*
Y-109833D02*
Y-106289D01*
X58210Y-109833D02*
X64903D01*
X58210D02*
Y-106289D01*
X579109Y-20555D02*
Y18945D01*
X630610D01*
Y-20555D02*
Y18945D01*
X579109Y-20555D02*
X630610D01*
X440846Y-163878D02*
Y-133760D01*
X404823Y-163878D02*
X440846D01*
X404823D02*
Y-133760D01*
X440846D01*
X158957Y-99104D02*
X163878D01*
Y-104025D02*
Y-99104D01*
X158957Y-104025D02*
X163878D01*
X158957D02*
Y-99104D01*
X82284Y3150D02*
X112205D01*
X82284D02*
Y21260D01*
X112205D01*
Y3150D02*
Y21260D01*
X597441Y-231299D02*
X604134D01*
Y-234842D02*
Y-231299D01*
X597441Y-234842D02*
X604134D01*
X597441D02*
Y-231299D01*
X599606Y-187879D02*
Y-184336D01*
Y-187879D02*
X606299D01*
Y-184336D01*
X599606D02*
X606299D01*
X597281Y-217062D02*
X622674D01*
Y-190645D01*
X597281D02*
X622674D01*
X597281Y-217062D02*
Y-190645D01*
X594291Y-151772D02*
Y-148228D01*
Y-151772D02*
X600984D01*
Y-148228D01*
X594291D02*
X600984D01*
X476772Y-269882D02*
Y-261614D01*
Y-269882D02*
X483858D01*
Y-261614D01*
X476772D02*
X483858D01*
X185630Y-98032D02*
X193898D01*
Y-90945D01*
X185630D02*
X193898D01*
X185630Y-98032D02*
Y-90945D01*
X173819Y-82284D02*
X205118D01*
Y4331D01*
X173819D02*
X205118D01*
X173819Y-82284D02*
Y4331D01*
X579134Y-292421D02*
Y-261122D01*
X492520D02*
X579134D01*
X492520Y-292421D02*
Y-261122D01*
Y-292421D02*
X579134D01*
X155548Y-137008D02*
Y-116142D01*
Y-137008D02*
X170902D01*
Y-116142D01*
X155548D02*
X170902D01*
X444882Y-162992D02*
X462992D01*
Y-133071D01*
X444882D02*
X462992D01*
X444882Y-162992D02*
Y-133071D01*
X466535Y-116929D02*
Y-87008D01*
X448425Y-116929D02*
X466535D01*
X448425D02*
Y-87008D01*
X466535D01*
X352898Y-120866D02*
X356835D01*
X352898D02*
Y-118898D01*
X356835D01*
Y-120866D02*
Y-118898D01*
X389670Y-113958D02*
Y-110021D01*
X391638D01*
Y-113958D02*
Y-110021D01*
X389670Y-113958D02*
X391638D01*
X356835Y-114173D02*
Y-112205D01*
X352898D02*
X356835D01*
X352898Y-114173D02*
Y-112205D01*
Y-114173D02*
X356835D01*
X381299Y-115354D02*
Y-108268D01*
X385236D01*
Y-115354D02*
Y-108268D01*
X381299Y-115354D02*
X385236D01*
X434009Y-200000D02*
Y-193701D01*
X422591Y-200000D02*
X434009D01*
X422591D02*
Y-193701D01*
X434009D01*
X45669Y3543D02*
Y21654D01*
Y3543D02*
X75590D01*
Y21654D01*
X45669D02*
X75590D01*
X370740Y-152717D02*
Y-137047D01*
X390425D01*
Y-152717D02*
Y-137047D01*
X370740Y-152717D02*
X390425D01*
X47638Y-60698D02*
Y-41013D01*
Y-60698D02*
X63307D01*
Y-41013D01*
X47638D02*
X63307D01*
X37008Y-22047D02*
Y-15748D01*
X24409D02*
X37008D01*
X24409Y-22047D02*
Y-15748D01*
Y-22047D02*
X37008D01*
X440158Y-123622D02*
X446457D01*
Y-111024D01*
X440158D02*
X446457D01*
X440158Y-123622D02*
Y-111024D01*
X453639Y-128347D02*
Y-122047D01*
Y-128347D02*
X466237D01*
Y-122047D01*
X453639D02*
X466237D01*
X375590Y-115354D02*
Y-108268D01*
X362205D02*
X375590D01*
X362205Y-115354D02*
Y-108268D01*
Y-115354D02*
X375590D01*
X331693Y-145079D02*
X361221D01*
Y-162795D02*
Y-145079D01*
X331693Y-162795D02*
X361221D01*
X331693D02*
Y-145079D01*
X331457Y-124803D02*
X361378D01*
Y-142913D02*
Y-124803D01*
X331457Y-142913D02*
X361378D01*
X331457D02*
Y-124803D01*
X43406Y-31594D02*
Y-1476D01*
X79429D01*
Y-31594D02*
Y-1476D01*
X43406Y-31594D02*
X79429D01*
X110630Y-86221D02*
Y-68110D01*
X80709D02*
X110630D01*
X80709Y-86221D02*
Y-68110D01*
Y-86221D02*
X110630D01*
X94685Y-64764D02*
Y-35236D01*
X112402D01*
Y-64764D02*
Y-35236D01*
X94685Y-64764D02*
X112402D01*
X87805Y-65266D02*
Y-58179D01*
X74419D02*
X87805D01*
X74419Y-65266D02*
Y-58179D01*
Y-65266D02*
X87805D01*
X451181Y-78150D02*
Y-74606D01*
Y-78150D02*
X457874D01*
Y-74606D01*
X451181D02*
X457874D01*
X98622Y-93898D02*
Y-90354D01*
X91929D02*
X98622D01*
X91929Y-93898D02*
Y-90354D01*
Y-93898D02*
X98622D01*
X93307Y-98622D02*
X97244D01*
Y-100591D02*
Y-98622D01*
X93307Y-100591D02*
X97244D01*
X93307D02*
Y-98622D01*
X467717Y-77362D02*
X471654D01*
X467717D02*
Y-75394D01*
X471654D01*
Y-77362D02*
Y-75394D01*
X37008Y-12992D02*
Y-6693D01*
X24409D02*
X37008D01*
X24409Y-12992D02*
Y-6693D01*
Y-12992D02*
X37008D01*
X597441Y-218701D02*
X604134D01*
Y-222244D02*
Y-218701D01*
X597441Y-222244D02*
X604134D01*
X597441D02*
Y-218701D01*
X277756Y-198819D02*
Y-191732D01*
X286024D01*
Y-198819D02*
Y-191732D01*
X277756Y-198819D02*
X286024D01*
X179367Y-129921D02*
Y-116929D01*
X185666D01*
Y-129921D02*
Y-116929D01*
X179367Y-129921D02*
X185666D01*
X169095Y-103937D02*
Y-100000D01*
X167126Y-103937D02*
X169095D01*
X167126D02*
Y-100000D01*
X169095D01*
X597441Y-225000D02*
X604134D01*
Y-228543D02*
Y-225000D01*
X597441Y-228543D02*
X604134D01*
X597441D02*
Y-225000D01*
X11811Y-238779D02*
Y-236811D01*
X7874D02*
X11811D01*
X7874Y-238779D02*
Y-236811D01*
Y-238779D02*
X11811D01*
X9055Y-350197D02*
Y-348228D01*
X5118D02*
X9055D01*
X5118Y-350197D02*
Y-348228D01*
Y-350197D02*
X9055D01*
X13189Y-296457D02*
X15157D01*
X13189Y-300394D02*
Y-296457D01*
Y-300394D02*
X15157D01*
Y-296457D01*
X13780Y-194291D02*
Y-192323D01*
X9843D02*
X13780D01*
X9843Y-194291D02*
Y-192323D01*
Y-194291D02*
X13780D01*
X322047Y-243898D02*
Y-235630D01*
Y-243898D02*
X329134D01*
Y-235630D01*
X322047D02*
X329134D01*
X25394Y-3740D02*
Y-197D01*
Y-3740D02*
X32087D01*
Y-197D01*
X25394D02*
X32087D01*
X25394Y3150D02*
Y6693D01*
Y3150D02*
X32087D01*
Y6693D01*
X25394D02*
X32087D01*
X25394Y10039D02*
Y13583D01*
Y10039D02*
X32087D01*
Y13583D01*
X25394D02*
X32087D01*
X25394Y16929D02*
Y20472D01*
Y16929D02*
X32087D01*
Y20472D01*
X25394D02*
X32087D01*
X146457Y-98036D02*
X150394D01*
X146457Y-105123D02*
Y-98036D01*
Y-105123D02*
X150394D01*
Y-98036D01*
X152165Y-99606D02*
X154134D01*
X152165Y-103543D02*
Y-99606D01*
Y-103543D02*
X154134D01*
Y-99606D01*
X608563Y-257776D02*
Y-255610D01*
Y-257776D02*
X612697D01*
Y-255610D01*
X608563D02*
X612697D01*
X609350Y-246911D02*
X621161D01*
Y-235100D01*
X609350D02*
X621161D01*
X609350Y-246911D02*
Y-235100D01*
X599213Y-301575D02*
Y-298425D01*
Y-301575D02*
X605512D01*
Y-298425D01*
X599213D02*
X605512D01*
X612598Y-303740D02*
Y-301772D01*
Y-303740D02*
X616535D01*
Y-301772D01*
X612598D02*
X616535D01*
X600098Y-293209D02*
Y-291043D01*
X595965D02*
X600098D01*
X595965Y-293209D02*
Y-291043D01*
Y-293209D02*
X600098D01*
X612697Y-262106D02*
Y-259941D01*
X608563D02*
X612697D01*
X608563Y-262106D02*
Y-259941D01*
Y-262106D02*
X612697D01*
X335827Y-297047D02*
Y-288779D01*
Y-297047D02*
X342913D01*
Y-288779D01*
X335827D02*
X342913D01*
X316929Y-297835D02*
Y-289567D01*
Y-297835D02*
X324016D01*
Y-289567D01*
X316929D02*
X324016D01*
X577776Y-76811D02*
Y-52323D01*
X549784D02*
X577776D01*
X549784Y-76811D02*
Y-52323D01*
Y-76811D02*
X577776D01*
X596063Y-80669D02*
X615748D01*
Y-65000D01*
X596063D02*
X615748D01*
X596063Y-80669D02*
Y-65000D01*
X136937Y-133468D02*
Y-123232D01*
X126701Y-133468D02*
X136937D01*
X126701D02*
Y-123232D01*
X136937D01*
M02*
